(kicad_pcb
	(version 20260206)
	(generator "pcbnew")
	(generator_version "10.0")
	(general
		(thickness 1.6)
		(legacy_teardrops no)
	)
	(paper "A4")
	(title_block
		(title "03242023_DA0F0TMBIJ0_F0T_Motherboard_J_brd_V01_OCP.brd")
		(comment 1 "Grand Teton / footprints 1198-1203 of 6105")
	)
	(layers
		(0 "F.Cu" signal "TOP")
		(4 "In1.Cu" signal "GND")
		(6 "In2.Cu" signal "IN1")
		(8 "In3.Cu" signal "GND1")
		(10 "In4.Cu" signal "IN2")
		(12 "In5.Cu" signal "GND2")
		(14 "In6.Cu" signal "IN3")
		(16 "In7.Cu" signal "GND3")
		(18 "In8.Cu" signal "VCC")
		(20 "In9.Cu" signal "VCC1")
		(22 "In10.Cu" signal "GND4")
		(24 "In11.Cu" signal "IN4")
		(26 "In12.Cu" signal "GND5")
		(28 "In13.Cu" signal "IN5")
		(30 "In14.Cu" signal "GND6")
		(32 "In15.Cu" signal "IN6")
		(34 "In16.Cu" signal "GND7")
		(2 "B.Cu" signal "BOTTOM")
		(9 "F.Adhes" user "F.Adhesive")
		(11 "B.Adhes" user "B.Adhesive")
		(13 "F.Paste" user "Package Geometry/Pastemask Top")
		(15 "B.Paste" user "Package Geometry/Pastemask Bottom")
		(5 "F.SilkS" user "Ref Des/Silkscreen Top")
		(7 "B.SilkS" user "Ref Des/Silkscreen Bottom")
		(1 "F.Mask" user "Board Geometry/Soldermask Top")
		(3 "B.Mask" user "Board Geometry/Soldermask Bottom")
		(17 "Dwgs.User" user "User.Drawings")
		(19 "Cmts.User" user "User.Comments")
		(21 "Eco1.User" user "User.Eco1")
		(23 "Eco2.User" user "User.Eco2")
		(25 "Edge.Cuts" user "Board Geometry/Outline")
		(27 "Margin" user)
		(31 "F.CrtYd" user "Package Geometry/Place Bound Top")
		(29 "B.CrtYd" user "Package Geometry/Place Bound Bottom")
		(35 "F.Fab" user "Ref Des/Assembly Top")
		(33 "B.Fab" user "Ref Des/Assembly Bottom")
	)
	(footprint ""
		(layer "F.Cu")
		(at 329.240388 5.463794 180)
		(property "Reference" "J84"
			(at -4.415282 -1.140206 90)
			(unlocked yes)
			(layer "F.SilkS")
			(effects
				(font
					(size 0.7874 0.5842)
					(thickness 0.1524)
				)
				(justify left)
			)
		)
		(property "Value" ""
			(at 0 0 180)
			(layer "F.Fab")
			(effects
				(font
					(size 1.27 1.27)
				)
			)
		)
		(duplicate_pad_numbers_are_jumpers no)
		(fp_line
			(start 1.2192 2.1082)
			(end -1.2192 2.1082)
			(stroke
				(width 0.1524)
				(type default)
			)
			(layer "F.SilkS")
		)
		(fp_line
			(start 1.2192 -2.1082)
			(end 1.2192 2.1082)
			(stroke
				(width 0.1524)
				(type default)
			)
			(layer "F.SilkS")
		)
		(fp_line
			(start -1.2192 2.1082)
			(end -1.2192 -2.1082)
			(stroke
				(width 0.1524)
				(type default)
			)
			(layer "F.SilkS")
		)
		(fp_line
			(start -1.2192 -2.1082)
			(end 1.2192 -2.1082)
			(stroke
				(width 0.1524)
				(type default)
			)
			(layer "F.SilkS")
		)
		(pad "" np_thru_hole circle
			(at -2.8829 -1.27 90)
			(size 1.0414 1.0414)
			(drill 1.0414)
			(layers "*.Cu" "*.Mask")
			(clearance 0.381)
			(thermal_gap 0.381)
		)
		(pad "" np_thru_hole circle
			(at -2.8829 1.27 90)
			(size 1.0414 1.0414)
			(drill 1.0414)
			(layers "*.Cu" "*.Mask")
			(clearance 0.381)
			(thermal_gap 0.381)
		)
		(pad "" np_thru_hole circle
			(at 3.4671 -1.27 90)
			(size 1.0414 1.0414)
			(drill 1.0414)
			(layers "*.Cu" "*.Mask")
			(clearance 0.381)
			(thermal_gap 0.381)
		)
		(pad "" np_thru_hole circle
			(at 3.4671 1.27 90)
			(size 1.0414 1.0414)
			(drill 1.0414)
			(layers "*.Cu" "*.Mask")
			(clearance 0.381)
			(thermal_gap 0.381)
		)
		(pad "1" smd rect
			(at 0.8255 -0.249936 90)
			(size 0.3048 0.508)
			(layers "F.Cu" "F.Mask" "F.Paste")
			(net "DELTA_L_85_10INCH_IN2_DN")
		)
		(pad "2" smd rect
			(at 0.8255 0.249936 90)
			(size 0.3048 0.508)
			(layers "F.Cu" "F.Mask" "F.Paste")
			(net "DELTA_L_85_10INCH_IN2_DP")
		)
		(pad "3" smd circle
			(at 0 0 180)
			(size 0 0)
			(layers "F.Cu" "F.Mask" "F.Paste")
			(net "DELTA_L_GND_1")
		)
		(zone
			(layer "F.Cu")
			(hatch none 0.5)
			(connect_pads
				(clearance 0)
			)
			(min_thickness 0.25)
			(keepout
				(tracks not_allowed)
				(vias allowed)
				(pads allowed)
				(copperpour not_allowed)
				(footprints allowed)
			)
			(placement
				(enabled no)
				(sheetname "")
			)
			(fill
				(thermal_gap 0.5)
				(thermal_bridge_width 0.5)
				(island_removal_mode 0)
			)
			(polygon
				(pts
					(xy 328.122788 6.012434) (xy 328.122788 5.91693) (xy 328.719688 5.91693) (xy 328.719688 5.51053)
					(xy 328.122788 5.51053) (xy 328.122788 5.417058) (xy 328.719688 5.417058) (xy 328.719688 5.010658)
					(xy 328.122788 5.010658) (xy 328.122788 4.915154) (xy 328.821288 4.915154) (xy 328.821288 6.012434)
				)
			)
		)
		(zone
			(layers "F.Cu" "B.Cu" "In1.Cu" "In2.Cu" "In3.Cu" "In4.Cu" "In5.Cu" "In6.Cu"
				"In7.Cu" "In8.Cu" "In9.Cu" "In10.Cu" "In11.Cu" "In12.Cu" "In13.Cu" "In14.Cu"
				"In15.Cu" "In16.Cu"
			)
			(hatch none 0.5)
			(connect_pads
				(clearance 0)
			)
			(min_thickness 0.25)
			(keepout
				(tracks not_allowed)
				(vias allowed)
				(pads allowed)
				(copperpour not_allowed)
				(footprints allowed)
			)
			(placement
				(enabled no)
				(sheetname "")
			)
			(fill
				(thermal_gap 0.5)
				(thermal_bridge_width 0.5)
				(island_removal_mode 0)
			)
			(polygon
				(pts
					(arc
						(start 326.700388 4.193794)
						(mid 324.846188 4.193794)
						(end 326.700388 4.193794)
					)
				)
			)
		)
		(zone
			(layers "F.Cu" "B.Cu" "In1.Cu" "In2.Cu" "In3.Cu" "In4.Cu" "In5.Cu" "In6.Cu"
				"In7.Cu" "In8.Cu" "In9.Cu" "In10.Cu" "In11.Cu" "In12.Cu" "In13.Cu" "In14.Cu"
				"In15.Cu" "In16.Cu"
			)
			(hatch none 0.5)
			(connect_pads
				(clearance 0)
			)
			(min_thickness 0.25)
			(keepout
				(tracks not_allowed)
				(vias allowed)
				(pads allowed)
				(copperpour not_allowed)
				(footprints allowed)
			)
			(placement
				(enabled no)
				(sheetname "")
			)
			(fill
				(thermal_gap 0.5)
				(thermal_bridge_width 0.5)
				(island_removal_mode 0)
			)
			(polygon
				(pts
					(arc
						(start 326.700388 6.733794)
						(mid 324.846188 6.733794)
						(end 326.700388 6.733794)
					)
				)
			)
		)
		(zone
			(layers "F.Cu" "B.Cu" "In1.Cu" "In2.Cu" "In3.Cu" "In4.Cu" "In5.Cu" "In6.Cu"
				"In7.Cu" "In8.Cu" "In9.Cu" "In10.Cu" "In11.Cu" "In12.Cu" "In13.Cu" "In14.Cu"
				"In15.Cu" "In16.Cu"
			)
			(hatch none 0.5)
			(connect_pads
				(clearance 0)
			)
			(min_thickness 0.25)
			(keepout
				(tracks not_allowed)
				(vias allowed)
				(pads allowed)
				(copperpour not_allowed)
				(footprints allowed)
			)
			(placement
				(enabled no)
				(sheetname "")
			)
			(fill
				(thermal_gap 0.5)
				(thermal_bridge_width 0.5)
				(island_removal_mode 0)
			)
			(polygon
				(pts
					(arc
						(start 333.050388 4.193794)
						(mid 331.196188 4.193794)
						(end 333.050388 4.193794)
					)
				)
			)
		)
		(zone
			(layers "F.Cu" "B.Cu" "In1.Cu" "In2.Cu" "In3.Cu" "In4.Cu" "In5.Cu" "In6.Cu"
				"In7.Cu" "In8.Cu" "In9.Cu" "In10.Cu" "In11.Cu" "In12.Cu" "In13.Cu" "In14.Cu"
				"In15.Cu" "In16.Cu"
			)
			(hatch none 0.5)
			(connect_pads
				(clearance 0)
			)
			(min_thickness 0.25)
			(keepout
				(tracks not_allowed)
				(vias allowed)
				(pads allowed)
				(copperpour not_allowed)
				(footprints allowed)
			)
			(placement
				(enabled no)
				(sheetname "")
			)
			(fill
				(thermal_gap 0.5)
				(thermal_bridge_width 0.5)
				(island_removal_mode 0)
			)
			(polygon
				(pts
					(arc
						(start 333.050388 6.733794)
						(mid 331.196188 6.733794)
						(end 333.050388 6.733794)
					)
				)
			)
		)
	)
	(footprint ""
		(layer "F.Cu")
		(at 329.124818 -23.803864 -90)
		(property "Reference" "R1871"
			(at 0 0 270)
			(layer "F.SilkS")
			(hide yes)
			(effects
				(font
					(size 1.27 1.27)
				)
			)
		)
		(property "Value" ""
			(at 0 0 270)
			(layer "F.Fab")
			(effects
				(font
					(size 1.27 1.27)
				)
			)
		)
		(duplicate_pad_numbers_are_jumpers no)
		(fp_line
			(start -0.7874 0.4064)
			(end -0.7874 -0.4064)
			(stroke
				(width 0.1524)
				(type default)
			)
			(layer "F.SilkS")
		)
		(fp_line
			(start 0.7874 0.4064)
			(end -0.7874 0.4064)
			(stroke
				(width 0.1524)
				(type default)
			)
			(layer "F.SilkS")
		)
		(fp_line
			(start -0.7874 -0.4064)
			(end 0.7874 -0.4064)
			(stroke
				(width 0.1524)
				(type default)
			)
			(layer "F.SilkS")
		)
		(fp_line
			(start 0.7874 -0.4064)
			(end 0.7874 0.4064)
			(stroke
				(width 0.1524)
				(type default)
			)
			(layer "F.SilkS")
		)
		(fp_line
			(start -0.67945 0.3048)
			(end -0.67945 -0.305054)
			(stroke
				(width 0.1)
				(type default)
			)
			(layer "F.Fab")
		)
		(fp_line
			(start -0.12065 0.3048)
			(end -0.67945 0.3048)
			(stroke
				(width 0.1)
				(type default)
			)
			(layer "F.Fab")
		)
		(fp_line
			(start 0.120396 0.3048)
			(end 0.120396 0.2794)
			(stroke
				(width 0.1)
				(type default)
			)
			(layer "F.Fab")
		)
		(fp_line
			(start 0.67945 0.3048)
			(end 0.120396 0.3048)
			(stroke
				(width 0.1)
				(type default)
			)
			(layer "F.Fab")
		)
		(fp_line
			(start -0.12065 0.2794)
			(end -0.12065 0.3048)
			(stroke
				(width 0.1)
				(type default)
			)
			(layer "F.Fab")
		)
		(fp_line
			(start 0.120396 0.2794)
			(end -0.12065 0.2794)
			(stroke
				(width 0.1)
				(type default)
			)
			(layer "F.Fab")
		)
		(fp_line
			(start -0.12065 -0.2794)
			(end 0.12065 -0.2794)
			(stroke
				(width 0.1)
				(type default)
			)
			(layer "F.Fab")
		)
		(fp_line
			(start 0.12065 -0.2794)
			(end 0.12065 -0.3048)
			(stroke
				(width 0.1)
				(type default)
			)
			(layer "F.Fab")
		)
		(fp_line
			(start 0.12065 -0.3048)
			(end 0.67945 -0.3048)
			(stroke
				(width 0.1)
				(type default)
			)
			(layer "F.Fab")
		)
		(fp_line
			(start 0.67945 -0.3048)
			(end 0.67945 0.3048)
			(stroke
				(width 0.1)
				(type default)
			)
			(layer "F.Fab")
		)
		(fp_line
			(start -0.67945 -0.305054)
			(end -0.12065 -0.305054)
			(stroke
				(width 0.1)
				(type default)
			)
			(layer "F.Fab")
		)
		(fp_line
			(start -0.12065 -0.305054)
			(end -0.12065 -0.2794)
			(stroke
				(width 0.1)
				(type default)
			)
			(layer "F.Fab")
		)
		(pad "1" smd circle
			(at -0.40005 0 270)
			(size 0 0)
			(layers "F.Cu" "F.Mask" "F.Paste")
			(net "ESPI_LAD0_DATA_IO0")
		)
		(pad "2" smd circle
			(at 0.40005 0 270)
			(size 0 0)
			(layers "F.Cu" "F.Mask" "F.Paste")
			(net "ESPI_LPC_LAD0_IO0")
		)
	)
	(footprint ""
		(layer "F.Cu")
		(at 68.644008 -171.77004 90)
		(property "Reference" "PC384"
			(at 0 0 90)
			(layer "F.SilkS")
			(hide yes)
			(effects
				(font
					(size 1.27 1.27)
				)
			)
		)
		(property "Value" ""
			(at 0 0 90)
			(layer "F.Fab")
			(effects
				(font
					(size 1.27 1.27)
				)
			)
		)
		(duplicate_pad_numbers_are_jumpers no)
		(fp_line
			(start 2.750058 0.999998)
			(end -2.750058 0.999998)
			(stroke
				(width 0.1524)
				(type default)
			)
			(layer "F.SilkS")
		)
		(fp_circle
			(center 0 0.999998)
			(end 0 3.750056)
			(stroke
				(width 0.1524)
				(type default)
			)
			(fill no)
			(layer "F.SilkS")
		)
		(fp_poly
			(pts
				(arc
					(start 2.750058 0.999998)
					(mid 0 3.750056)
					(end -2.750058 0.999998)
				)
			)
			(stroke
				(width 0)
				(type default)
			)
			(fill yes)
			(layer "F.SilkS")
		)
		(fp_circle
			(center 0 0.999998)
			(end 0 3.750056)
			(stroke
				(width 0.1)
				(type default)
			)
			(fill no)
			(layer "F.Fab")
		)
		(pad "1" thru_hole rect
			(at 0 0 90)
			(size 1.5748 1.5748)
			(drill 1.0668)
			(layers "*.Cu" "*.Mask")
			(remove_unused_layers no)
			(net "PVCCD_HV_CPU1")
			(clearance 0)
			(padstack
				(mode front_inner_back)
				(layer "Inner"
					(shape circle)
					(size 1.5748 1.5748)
					(clearance 0)
				)
				(layer "B.Cu"
					(shape rect)
					(size 1.5748 1.5748)
					(clearance 0)
				)
			)
		)
		(pad "2" thru_hole circle
			(at 0 1.999996 90)
			(size 1.5748 1.5748)
			(drill 1.0668)
			(layers "*.Cu" "*.Mask")
			(remove_unused_layers no)
			(net "GND")
			(clearance 0)
		)
	)
	(footprint ""
		(layer "F.Cu")
		(at 145.59534 -36.761928)
		(property "Reference" "U243"
			(at -1.016 -1.80213 0)
			(unlocked yes)
			(layer "F.SilkS")
			(effects
				(font
					(size 0.7874 0.5842)
					(thickness 0.1524)
				)
			)
		)
		(property "Value" ""
			(at 0 0 0)
			(layer "F.Fab")
			(effects
				(font
					(size 1.27 1.27)
				)
			)
		)
		(duplicate_pad_numbers_are_jumpers no)
		(fp_line
			(start -1.7272 1.1176)
			(end -1.7272 -1.1176)
			(stroke
				(width 0.1524)
				(type default)
			)
			(layer "F.SilkS")
		)
		(fp_line
			(start -0.254 -1.1176)
			(end -1.7272 -1.1176)
			(stroke
				(width 0.1524)
				(type default)
			)
			(layer "F.SilkS")
		)
		(fp_line
			(start 0 -0.7366)
			(end -0.254 -1.1176)
			(stroke
				(width 0.1524)
				(type default)
			)
			(layer "F.SilkS")
		)
		(fp_line
			(start 0.254 -1.1176)
			(end 0 -0.7366)
			(stroke
				(width 0.1524)
				(type default)
			)
			(layer "F.SilkS")
		)
		(fp_line
			(start 1.7272 -1.1176)
			(end 0.254 -1.1176)
			(stroke
				(width 0.1524)
				(type default)
			)
			(layer "F.SilkS")
		)
		(fp_line
			(start 1.7272 -1.1176)
			(end 1.7272 1.1176)
			(stroke
				(width 0.1524)
				(type default)
			)
			(layer "F.SilkS")
		)
		(fp_line
			(start 1.7272 1.1176)
			(end -1.7272 1.1176)
			(stroke
				(width 0.1524)
				(type default)
			)
			(layer "F.SilkS")
		)
		(fp_poly
			(pts
				(xy -2.7178 -0.268986) (xy -2.7178 -1.030986) (xy -1.9558 -0.649986)
			)
			(stroke
				(width 0)
				(type default)
			)
			(fill yes)
			(layer "F.SilkS")
		)
		(fp_line
			(start -1.5748 -1.1176)
			(end -1.5748 1.1176)
			(stroke
				(width 0.1)
				(type default)
			)
			(layer "F.Fab")
		)
		(fp_line
			(start -1.5748 1.1176)
			(end 1.5748 1.1176)
			(stroke
				(width 0.1)
				(type default)
			)
			(layer "F.Fab")
		)
		(fp_line
			(start 1.5748 -1.1176)
			(end -1.5748 -1.1176)
			(stroke
				(width 0.1)
				(type default)
			)
			(layer "F.Fab")
		)
		(fp_line
			(start 1.5748 1.1176)
			(end 1.5748 -1.1176)
			(stroke
				(width 0.1)
				(type default)
			)
			(layer "F.Fab")
		)
		(fp_poly
			(pts
				(xy -1.9558 -0.649986) (xy -2.7178 -0.268986) (xy -2.7178 -1.030986)
			)
			(stroke
				(width 0)
				(type default)
			)
			(fill yes)
			(layer "F.Fab")
		)
		(pad "1" smd rect
			(at -0.999998 -0.649986 270)
			(size 0.3556 1.1176)
			(layers "F.Cu" "F.Mask" "F.Paste")
			(net "OCP_SFF_NOT_PRSNT_RBT_ARB_IN")
		)
		(pad "2" smd rect
			(at -0.999998 0 270)
			(size 0.3556 1.1176)
			(layers "F.Cu" "F.Mask" "F.Paste")
			(net "GND")
		)
		(pad "3" smd rect
			(at -0.999998 0.649986 270)
			(size 0.3556 1.1176)
			(layers "F.Cu" "F.Mask" "F.Paste")
			(net "OCP_SFF_RBT_ARB_OUT")
		)
		(pad "4" smd rect
			(at 0.999998 0.649986 270)
			(size 0.3556 1.1176)
			(layers "F.Cu" "F.Mask" "F.Paste")
			(net "OCP_SFF_RBT_ARB_IN_MUX2")
		)
		(pad "5" smd rect
			(at 0.999998 0 270)
			(size 0.3556 1.1176)
			(layers "F.Cu" "F.Mask" "F.Paste")
			(net "P3V3_AUX")
		)
		(pad "6" smd rect
			(at 0.999998 -0.649986 270)
			(size 0.3556 1.1176)
			(layers "F.Cu" "F.Mask" "F.Paste")
			(net "OCP_SFF_PRSNT_ALL_R1_N")
		)
	)
	(footprint ""
		(layer "F.Cu")
		(at 29.332428 -99.586034 180)
		(property "Reference" "R3864"
			(at 0 0 180)
			(layer "F.SilkS")
			(hide yes)
			(effects
				(font
					(size 1.27 1.27)
				)
			)
		)
		(property "Value" ""
			(at 0 0 180)
			(layer "F.Fab")
			(effects
				(font
					(size 1.27 1.27)
				)
			)
		)
		(duplicate_pad_numbers_are_jumpers no)
		(fp_line
			(start 0.7874 0.4064)
			(end -0.7874 0.4064)
			(stroke
				(width 0.1524)
				(type default)
			)
			(layer "F.SilkS")
		)
		(fp_line
			(start 0.7874 -0.4064)
			(end 0.7874 0.4064)
			(stroke
				(width 0.1524)
				(type default)
			)
			(layer "F.SilkS")
		)
		(fp_line
			(start -0.7874 0.4064)
			(end -0.7874 -0.4064)
			(stroke
				(width 0.1524)
				(type default)
			)
			(layer "F.SilkS")
		)
		(fp_line
			(start -0.7874 -0.4064)
			(end 0.7874 -0.4064)
			(stroke
				(width 0.1524)
				(type default)
			)
			(layer "F.SilkS")
		)
		(fp_line
			(start 0.67945 0.3048)
			(end 0.120396 0.3048)
			(stroke
				(width 0.1)
				(type default)
			)
			(layer "F.Fab")
		)
		(fp_line
			(start 0.67945 -0.3048)
			(end 0.67945 0.3048)
			(stroke
				(width 0.1)
				(type default)
			)
			(layer "F.Fab")
		)
		(fp_line
			(start 0.12065 -0.2794)
			(end 0.12065 -0.3048)
			(stroke
				(width 0.1)
				(type default)
			)
			(layer "F.Fab")
		)
		(fp_line
			(start 0.12065 -0.3048)
			(end 0.67945 -0.3048)
			(stroke
				(width 0.1)
				(type default)
			)
			(layer "F.Fab")
		)
		(fp_line
			(start 0.120396 0.3048)
			(end 0.120396 0.2794)
			(stroke
				(width 0.1)
				(type default)
			)
			(layer "F.Fab")
		)
		(fp_line
			(start 0.120396 0.2794)
			(end -0.12065 0.2794)
			(stroke
				(width 0.1)
				(type default)
			)
			(layer "F.Fab")
		)
		(fp_line
			(start -0.12065 0.3048)
			(end -0.67945 0.3048)
			(stroke
				(width 0.1)
				(type default)
			)
			(layer "F.Fab")
		)
		(fp_line
			(start -0.12065 0.2794)
			(end -0.12065 0.3048)
			(stroke
				(width 0.1)
				(type default)
			)
			(layer "F.Fab")
		)
		(fp_line
			(start -0.12065 -0.2794)
			(end 0.12065 -0.2794)
			(stroke
				(width 0.1)
				(type default)
			)
			(layer "F.Fab")
		)
		(fp_line
			(start -0.12065 -0.305054)
			(end -0.12065 -0.2794)
			(stroke
				(width 0.1)
				(type default)
			)
			(layer "F.Fab")
		)
		(fp_line
			(start -0.67945 0.3048)
			(end -0.67945 -0.305054)
			(stroke
				(width 0.1)
				(type default)
			)
			(layer "F.Fab")
		)
		(fp_line
			(start -0.67945 -0.305054)
			(end -0.12065 -0.305054)
			(stroke
				(width 0.1)
				(type default)
			)
			(layer "F.Fab")
		)
		(pad "1" smd rect
			(at -0.40005 0)
			(size 0.4572 0.508)
			(layers "F.Cu" "F.Mask" "F.Paste")
			(net "P12V_OCP_SFF_ISENSE_MPS_MAM")
		)
		(pad "2" smd rect
			(at 0.40005 0)
			(size 0.4572 0.508)
			(layers "F.Cu" "F.Mask" "F.Paste")
			(net "P12V_OCP_SFF_ISENSE_MAM")
		)
	)
	(footprint ""
		(layer "F.Cu")
		(at 73.806558 -408.517344 -90)
		(property "Reference" "C692"
			(at 0 0 270)
			(layer "F.SilkS")
			(hide yes)
			(effects
				(font
					(size 1.27 1.27)
				)
			)
		)
		(property "Value" ""
			(at 0 0 270)
			(layer "F.Fab")
			(effects
				(font
					(size 1.27 1.27)
				)
			)
		)
		(duplicate_pad_numbers_are_jumpers no)
		(fp_line
			(start -0.299974 0.150114)
			(end -0.299974 -0.150114)
			(stroke
				(width 0.1)
				(type default)
			)
			(layer "F.Fab")
		)
		(fp_line
			(start 0.299974 0.150114)
			(end -0.299974 0.150114)
			(stroke
				(width 0.1)
				(type default)
			)
			(layer "F.Fab")
		)
		(fp_line
			(start -0.299974 -0.150114)
			(end 0.299974 -0.150114)
			(stroke
				(width 0.1)
				(type default)
			)
			(layer "F.Fab")
		)
		(fp_line
			(start 0.299974 -0.150114)
			(end 0.299974 0.150114)
			(stroke
				(width 0.1)
				(type default)
			)
			(layer "F.Fab")
		)
		(pad "1" smd rect
			(at -0.2667 0 270)
			(size 0.3048 0.381)
			(layers "F.Cu" "F.Mask" "F.Paste")
			(net "P5E_CPU1_PE4_TX_C_DN<8>")
		)
		(pad "2" smd rect
			(at 0.2667 0 270)
			(size 0.3048 0.381)
			(layers "F.Cu" "F.Mask" "F.Paste")
			(net "P5E_CPU1_PE4_TX_DN<8>")
		)
	)
)
